FILE_TYPE = MULTI_PHYS_TABLE;

PART 'AP22811AW57'

{========================================================================================}
:VALUE          | PART_TYPE | MATERIAL | PART_NUMBER       = STANDARD    | LIFECYCLE     | PART_NUMBER       | JEDEC_TYPE           | DESCRIPTION                             | MANUFTR | MANUF_PN       | RD_CMPLS_LVL | CMPLS_LVL | FROM_PJ       | CLASS | DIP_SMD | DATA                   | EE_CHECK_LIST | FP_ECN           | PSL | CREATOR | STATUS | MSD  | ESD_CDM | ESD_HBM | ESD_MM | PIN_LENGTH_SHORT_PIN | PIN_LENGTH_LONG_PIN | CREATEDAY  ;
{========================================================================================}
 'AP22811AW5-7' | 'SMLF'    | 'IC'     | 'AL022811000'(!)  = ''          | ''            | 'AL022811000'     |'SOT25-5_0-95_3X1-6'| 'IC OTHER(5P)AP22811AW5-7(SOT25)'       | 'DDS'   | 'AP22811AW5-7' | 'EP(V1)'     | 'EP(V1)'  | 'JBP-JACK'    | 'IC'  | ''      | 'DDS_AP22811AW5-7.pdf' | ''            | ''               | ''  | ''      | ''     | 'NA' | 'NA'    | '2KV'   | '200V' | '0 MILS'             | '0 MILS'            | '20190201'
 'AP22811AW5-7' | 'SMLF'    | 'EMPTY'  | 'AL022811000'(!)  = ''          | ''            | 'AL022811000'     |'SOT25-5_0-95_3X1-6'| 'IC OTHER(5P)AP22811AW5-7(SOT25)'       | 'DDS'   | 'AP22811AW5-7' | 'EP(V1)'     | 'EP(V1)'  | 'JBP-JACK'    | 'IC'  | ''      | 'DDS_AP22811AW5-7.pdf' | ''            | ''               | ''  | ''      | ''     | 'NA' | 'NA'    | '2KV'   | '200V' | '0 MILS'             | '0 MILS'            | '20190201'
 'AP22811AW5-7' | 'SMLF'    | 'IC'     | 'AL022811003'(!)  = ''          | ''            | 'AL022811003'     |'SOT25-5_0-95_3X1-6'| 'IC (5P)AP22811AW5-7(SOT25)AMAASN'      | 'DDS'   | 'AP22811AW5-7' | 'EP(V1)'     | 'EP(V1)'  | 'A5G-JASMINE' | 'IC'  | ''      | 'DDS_AP22811AW5-7.pdf' | ''            | ''               | ''  | ''      | ''     | ''   | ''      | ''      | ''     | '0 MILS'             | '0 MILS'            | '20230428'
 'AP22811AW5-7' | 'SMLF'    | 'EMPTY'  | 'AL022811003'(!)  = ''          | ''            | 'AL022811003'     |'SOT25-5_0-95_3X1-6'| 'IC (5P)AP22811AW5-7(SOT25)AMAASN'      | 'DDS'   | 'AP22811AW5-7' | 'EP(V1)'     | 'EP(V1)'  | 'A5G-JASMINE' | 'IC'  | ''      | 'DDS_AP22811AW5-7.pdf' | ''            | ''               | ''  | ''      | ''     | ''   | ''      | ''      | ''     | '0 MILS'             | '0 MILS'            | '20230428'
 'AP22811AW5-7' | 'SMLF'    | 'IC'     | 'AL022811000SEL1'(!) = ''               | ''               | 'AL022811000SEL1' |'SOT25-5_0-95_3X1-6'| 'IC OTHER(5P)AP22811AW5-7(SOT25)SELASN' | 'DDS'   | 'AP22811AW5-7' | 'EP(V1)'     | 'EP(V1)'  | 'JBP-JACK'    | 'IC'  | ''      | 'DDS_AP22811AW5-7.pdf' | ''            | 'SEL_15QPN.xlsx' | ''  | ''      | ''     | 'NA' | 'NA'    | '2KV'   | '200V' | '0 MILS'             | '0 MILS'            | '20230719'
 'AP22811AW5-7' | 'SMLF'    | 'EMPTY'  | 'AL022811000SEL1'(!) = ''               | ''               | 'AL022811000SEL1' |'SOT25-5_0-95_3X1-6'| 'IC OTHER(5P)AP22811AW5-7(SOT25)SELASN' | 'DDS'   | 'AP22811AW5-7' | 'EP(V1)'     | 'EP(V1)'  | 'JBP-JACK'    | 'IC'  | ''      | 'DDS_AP22811AW5-7.pdf' | ''            | 'SEL_15QPN.xlsx' | ''  | ''      | ''     | 'NA' | 'NA'    | '2KV'   | '200V' | '0 MILS'             | '0 MILS'            | '20230719'

END_PART

END.

